(kicad_pcb
	(version 20260206)
	(generator "pcbnew")
	(generator_version "10.0")
	(general
		(thickness 1.6)
		(legacy_teardrops no)
	)
	(paper "A4")
	(title_block
		(title "01162023_DA0F0TEBIF0_F0T_Expander_BD_F_brd_V02_OCP.brd")
		(comment 1 "Grand Teton / footprints 5326-5328 of 9728")
	)
	(layers
		(0 "F.Cu" signal "TOP")
		(4 "In1.Cu" signal "GND")
		(6 "In2.Cu" signal "VCC")
		(8 "In3.Cu" signal "VCC1")
		(10 "In4.Cu" signal "GND1")
		(12 "In5.Cu" signal "IN1")
		(14 "In6.Cu" signal "GND2")
		(16 "In7.Cu" signal "IN2")
		(18 "In8.Cu" signal "GND3")
		(20 "In9.Cu" signal "IN3")
		(22 "In10.Cu" signal "GND4")
		(24 "In11.Cu" signal "IN4")
		(26 "In12.Cu" signal "GND5")
		(28 "In13.Cu" signal "IN5")
		(30 "In14.Cu" signal "GND6")
		(32 "In15.Cu" signal "IN6")
		(34 "In16.Cu" signal "GND7")
		(2 "B.Cu" signal "BOTTOM")
		(9 "F.Adhes" user "F.Adhesive")
		(11 "B.Adhes" user "B.Adhesive")
		(13 "F.Paste" user "Package Geometry/Pastemask Top")
		(15 "B.Paste" user "Package Geometry/Pastemask Bottom")
		(5 "F.SilkS" user "Ref Des/Silkscreen Top")
		(7 "B.SilkS" user "Ref Des/Silkscreen Bottom")
		(1 "F.Mask" user "Board Geometry/Soldermask Top")
		(3 "B.Mask" user "Board Geometry/Soldermask Bottom")
		(17 "Dwgs.User" user "User.Drawings")
		(19 "Cmts.User" user "User.Comments")
		(21 "Eco1.User" user "User.Eco1")
		(23 "Eco2.User" user "User.Eco2")
		(25 "Edge.Cuts" user "Board Geometry/Outline")
		(27 "Margin" user)
		(31 "F.CrtYd" user "Package Geometry/Place Bound Top")
		(29 "B.CrtYd" user "Package Geometry/Place Bound Bottom")
		(35 "F.Fab" user "Ref Des/Assembly Top")
		(33 "B.Fab" user "Ref Des/Assembly Bottom")
	)
	(footprint ""
		(layer "F.Cu")
		(at 106.274362 -6.739636)
		(property "Reference" "R1656"
			(at 0 0 0)
			(layer "F.SilkS")
			(hide yes)
			(effects
				(font
					(size 1.27 1.27)
				)
			)
		)
		(property "Value" ""
			(at 0 0 0)
			(layer "F.Fab")
			(effects
				(font
					(size 1.27 1.27)
				)
			)
		)
		(duplicate_pad_numbers_are_jumpers no)
		(fp_line
			(start -0.7874 -0.4064)
			(end 0.7874 -0.4064)
			(stroke
				(width 0.1524)
				(type default)
			)
			(layer "F.SilkS")
		)
		(fp_line
			(start -0.7874 0.4064)
			(end -0.7874 -0.4064)
			(stroke
				(width 0.1524)
				(type default)
			)
			(layer "F.SilkS")
		)
		(fp_line
			(start 0.7874 -0.4064)
			(end 0.7874 0.4064)
			(stroke
				(width 0.1524)
				(type default)
			)
			(layer "F.SilkS")
		)
		(fp_line
			(start 0.7874 0.4064)
			(end -0.7874 0.4064)
			(stroke
				(width 0.1524)
				(type default)
			)
			(layer "F.SilkS")
		)
		(fp_line
			(start -0.67945 -0.305054)
			(end -0.12065 -0.305054)
			(stroke
				(width 0.1)
				(type default)
			)
			(layer "F.Fab")
		)
		(fp_line
			(start -0.67945 0.3048)
			(end -0.67945 -0.305054)
			(stroke
				(width 0.1)
				(type default)
			)
			(layer "F.Fab")
		)
		(fp_line
			(start -0.12065 -0.305054)
			(end -0.12065 -0.2794)
			(stroke
				(width 0.1)
				(type default)
			)
			(layer "F.Fab")
		)
		(fp_line
			(start -0.12065 -0.2794)
			(end 0.12065 -0.2794)
			(stroke
				(width 0.1)
				(type default)
			)
			(layer "F.Fab")
		)
		(fp_line
			(start -0.12065 0.2794)
			(end -0.12065 0.3048)
			(stroke
				(width 0.1)
				(type default)
			)
			(layer "F.Fab")
		)
		(fp_line
			(start -0.12065 0.3048)
			(end -0.67945 0.3048)
			(stroke
				(width 0.1)
				(type default)
			)
			(layer "F.Fab")
		)
		(fp_line
			(start 0.120396 0.2794)
			(end -0.12065 0.2794)
			(stroke
				(width 0.1)
				(type default)
			)
			(layer "F.Fab")
		)
		(fp_line
			(start 0.120396 0.3048)
			(end 0.120396 0.2794)
			(stroke
				(width 0.1)
				(type default)
			)
			(layer "F.Fab")
		)
		(fp_line
			(start 0.12065 -0.3048)
			(end 0.67945 -0.3048)
			(stroke
				(width 0.1)
				(type default)
			)
			(layer "F.Fab")
		)
		(fp_line
			(start 0.12065 -0.2794)
			(end 0.12065 -0.3048)
			(stroke
				(width 0.1)
				(type default)
			)
			(layer "F.Fab")
		)
		(fp_line
			(start 0.67945 -0.3048)
			(end 0.67945 0.3048)
			(stroke
				(width 0.1)
				(type default)
			)
			(layer "F.Fab")
		)
		(fp_line
			(start 0.67945 0.3048)
			(end 0.120396 0.3048)
			(stroke
				(width 0.1)
				(type default)
			)
			(layer "F.Fab")
		)
		(pad "1" smd circle
			(at -0.40005 0)
			(size 0 0)
			(layers "F.Cu" "F.Mask" "F.Paste")
			(net "SMB_BIC_I2C9_MUX0_SSD3_R_SDA")
		)
		(pad "2" smd circle
			(at 0.40005 0)
			(size 0 0)
			(layers "F.Cu" "F.Mask" "F.Paste")
			(net "SMB_ISO_SSD3_SDA")
		)
	)
	(footprint ""
		(layer "F.Cu")
		(at 226.19716 -266.873228)
		(property "Reference" "R6132"
			(at 0 0 0)
			(layer "F.SilkS")
			(hide yes)
			(effects
				(font
					(size 1.27 1.27)
				)
			)
		)
		(property "Value" ""
			(at 0 0 0)
			(layer "F.Fab")
			(effects
				(font
					(size 1.27 1.27)
				)
			)
		)
		(duplicate_pad_numbers_are_jumpers no)
		(fp_line
			(start -2.576322 -1.1303)
			(end 2.576322 -1.1303)
			(stroke
				(width 0.1524)
				(type default)
			)
			(layer "F.SilkS")
		)
		(fp_line
			(start -2.576322 1.1303)
			(end -2.576322 -1.1303)
			(stroke
				(width 0.1524)
				(type default)
			)
			(layer "F.SilkS")
		)
		(fp_line
			(start 2.576322 -1.1303)
			(end 2.576322 1.1303)
			(stroke
				(width 0.1524)
				(type default)
			)
			(layer "F.SilkS")
		)
		(fp_line
			(start 2.576322 1.1303)
			(end -2.576322 1.1303)
			(stroke
				(width 0.1524)
				(type default)
			)
			(layer "F.SilkS")
		)
		(fp_line
			(start -1.649984 -0.899922)
			(end -1.649984 0.899922)
			(stroke
				(width 0.1)
				(type default)
			)
			(layer "F.Fab")
		)
		(fp_line
			(start -1.649984 0.899922)
			(end 1.649984 0.899922)
			(stroke
				(width 0.1)
				(type default)
			)
			(layer "F.Fab")
		)
		(fp_line
			(start 1.649984 -0.899922)
			(end -1.649984 -0.899922)
			(stroke
				(width 0.1)
				(type default)
			)
			(layer "F.Fab")
		)
		(fp_line
			(start 1.649984 0.899922)
			(end 1.649984 -0.899922)
			(stroke
				(width 0.1)
				(type default)
			)
			(layer "F.Fab")
		)
		(pad "1A" smd rect
			(at -1.700022 0)
			(size 1.4986 2.0066)
			(layers "F.Cu" "F.Mask" "F.Paste")
			(net "P1V25_PEX1")
		)
		(pad "1B" smd rect
			(at -1.077722 0)
			(size 0.254 0.508)
			(layers "F.Cu" "F.Mask" "F.Paste")
			(net "P1V25_PEX1")
		)
		(pad "2A" smd rect
			(at 1.700022 0)
			(size 1.4986 2.0066)
			(layers "F.Cu" "F.Mask" "F.Paste")
			(net "P1V25_SERDES_VDDPLL_PEX1")
		)
		(pad "2B" smd rect
			(at 1.077722 0)
			(size 0.254 0.508)
			(layers "F.Cu" "F.Mask" "F.Paste")
			(net "P1V25_SERDES_VDDPLL_PEX1")
		)
	)
	(footprint ""
		(layer "F.Cu")
		(at 166.58209 -37.025072)
		(property "Reference" "R5677"
			(at 0 0 0)
			(layer "F.SilkS")
			(hide yes)
			(effects
				(font
					(size 1.27 1.27)
				)
			)
		)
		(property "Value" ""
			(at 0 0 0)
			(layer "F.Fab")
			(effects
				(font
					(size 1.27 1.27)
				)
			)
		)
		(duplicate_pad_numbers_are_jumpers no)
		(fp_line
			(start -0.7874 -0.4064)
			(end 0.7874 -0.4064)
			(stroke
				(width 0.1524)
				(type default)
			)
			(layer "F.SilkS")
		)
		(fp_line
			(start -0.7874 0.4064)
			(end -0.7874 -0.4064)
			(stroke
				(width 0.1524)
				(type default)
			)
			(layer "F.SilkS")
		)
		(fp_line
			(start 0.7874 -0.4064)
			(end 0.7874 0.4064)
			(stroke
				(width 0.1524)
				(type default)
			)
			(layer "F.SilkS")
		)
		(fp_line
			(start 0.7874 0.4064)
			(end -0.7874 0.4064)
			(stroke
				(width 0.1524)
				(type default)
			)
			(layer "F.SilkS")
		)
		(fp_line
			(start -0.67945 -0.305054)
			(end -0.12065 -0.305054)
			(stroke
				(width 0.1)
				(type default)
			)
			(layer "F.Fab")
		)
		(fp_line
			(start -0.67945 0.3048)
			(end -0.67945 -0.305054)
			(stroke
				(width 0.1)
				(type default)
			)
			(layer "F.Fab")
		)
		(fp_line
			(start -0.12065 -0.305054)
			(end -0.12065 -0.2794)
			(stroke
				(width 0.1)
				(type default)
			)
			(layer "F.Fab")
		)
		(fp_line
			(start -0.12065 -0.2794)
			(end 0.12065 -0.2794)
			(stroke
				(width 0.1)
				(type default)
			)
			(layer "F.Fab")
		)
		(fp_line
			(start -0.12065 0.2794)
			(end -0.12065 0.3048)
			(stroke
				(width 0.1)
				(type default)
			)
			(layer "F.Fab")
		)
		(fp_line
			(start -0.12065 0.3048)
			(end -0.67945 0.3048)
			(stroke
				(width 0.1)
				(type default)
			)
			(layer "F.Fab")
		)
		(fp_line
			(start 0.120396 0.2794)
			(end -0.12065 0.2794)
			(stroke
				(width 0.1)
				(type default)
			)
			(layer "F.Fab")
		)
		(fp_line
			(start 0.120396 0.3048)
			(end 0.120396 0.2794)
			(stroke
				(width 0.1)
				(type default)
			)
			(layer "F.Fab")
		)
		(fp_line
			(start 0.12065 -0.3048)
			(end 0.67945 -0.3048)
			(stroke
				(width 0.1)
				(type default)
			)
			(layer "F.Fab")
		)
		(fp_line
			(start 0.12065 -0.2794)
			(end 0.12065 -0.3048)
			(stroke
				(width 0.1)
				(type default)
			)
			(layer "F.Fab")
		)
		(fp_line
			(start 0.67945 -0.3048)
			(end 0.67945 0.3048)
			(stroke
				(width 0.1)
				(type default)
			)
			(layer "F.Fab")
		)
		(fp_line
			(start 0.67945 0.3048)
			(end 0.120396 0.3048)
			(stroke
				(width 0.1)
				(type default)
			)
			(layer "F.Fab")
		)
		(pad "1" smd circle
			(at -0.40005 0)
			(size 0 0)
			(layers "F.Cu" "F.Mask" "F.Paste")
			(net "RST_SMB_SSD_R_N")
		)
		(pad "2" smd circle
			(at 0.40005 0)
			(size 0 0)
			(layers "F.Cu" "F.Mask" "F.Paste")
			(net "RST_SMB_SSD6_N")
		)
	)
)
